(kicad_pcb
	(version 20260206)
	(generator "pcbnew")
	(generator_version "10.0")
	(general
		(thickness 1.6)
		(legacy_teardrops no)
	)
	(paper "A4")
	(title_block
		(title "04192023_DAF0TMB3IC0_F0TG_MB_C_brd_V02_OCP.brd")
		(comment 1 "Grand Teton / footprints 1960-1964 of 8354")
	)
	(layers
		(0 "F.Cu" signal "TOP")
		(4 "In1.Cu" signal "GND")
		(6 "In2.Cu" signal "IN1")
		(8 "In3.Cu" signal "GND1")
		(10 "In4.Cu" signal "IN2")
		(12 "In5.Cu" signal "GND2")
		(14 "In6.Cu" signal "IN3")
		(16 "In7.Cu" signal "GND3")
		(18 "In8.Cu" signal "VCC")
		(20 "In9.Cu" signal "VCC1")
		(22 "In10.Cu" signal "GND4")
		(24 "In11.Cu" signal "IN4")
		(26 "In12.Cu" signal "GND5")
		(28 "In13.Cu" signal "IN5")
		(30 "In14.Cu" signal "GND6")
		(32 "In15.Cu" signal "IN6")
		(34 "In16.Cu" signal "GND7")
		(2 "B.Cu" signal "BOTTOM")
		(9 "F.Adhes" user "F.Adhesive")
		(11 "B.Adhes" user "B.Adhesive")
		(13 "F.Paste" user "Package Geometry/Pastemask Top")
		(15 "B.Paste" user "Package Geometry/Pastemask Bottom")
		(5 "F.SilkS" user "Ref Des/Silkscreen Top")
		(7 "B.SilkS" user "Ref Des/Silkscreen Bottom")
		(1 "F.Mask" user "Board Geometry/Soldermask Top")
		(3 "B.Mask" user "Board Geometry/Soldermask Bottom")
		(17 "Dwgs.User" user "User.Drawings")
		(19 "Cmts.User" user "User.Comments")
		(21 "Eco1.User" user "User.Eco1")
		(23 "Eco2.User" user "User.Eco2")
		(25 "Edge.Cuts" user "Board Geometry/Outline")
		(27 "Margin" user)
		(31 "F.CrtYd" user "Package Geometry/Place Bound Top")
		(29 "B.CrtYd" user "Package Geometry/Place Bound Bottom")
		(35 "F.Fab" user "Ref Des/Assembly Top")
		(33 "B.Fab" user "Ref Des/Assembly Bottom")
	)
	(footprint ""
		(layer "F.Cu")
		(at 100.285296 -422.43248 90)
		(property "Reference" "R4195"
			(at 0 0 90)
			(layer "F.SilkS")
			(hide yes)
			(effects
				(font
					(size 1.27 1.27)
				)
			)
		)
		(property "Value" ""
			(at 0 0 90)
			(layer "F.Fab")
			(effects
				(font
					(size 1.27 1.27)
				)
			)
		)
		(duplicate_pad_numbers_are_jumpers no)
		(fp_line
			(start 0.7874 -0.4064)
			(end 0.7874 0.4064)
			(stroke
				(width 0.1524)
				(type default)
			)
			(layer "F.SilkS")
		)
		(fp_line
			(start -0.7874 -0.4064)
			(end 0.7874 -0.4064)
			(stroke
				(width 0.1524)
				(type default)
			)
			(layer "F.SilkS")
		)
		(fp_line
			(start 0.7874 0.4064)
			(end -0.7874 0.4064)
			(stroke
				(width 0.1524)
				(type default)
			)
			(layer "F.SilkS")
		)
		(fp_line
			(start -0.7874 0.4064)
			(end -0.7874 -0.4064)
			(stroke
				(width 0.1524)
				(type default)
			)
			(layer "F.SilkS")
		)
		(fp_line
			(start -0.12065 -0.305054)
			(end -0.12065 -0.2794)
			(stroke
				(width 0.1)
				(type default)
			)
			(layer "F.Fab")
		)
		(fp_line
			(start -0.67945 -0.305054)
			(end -0.12065 -0.305054)
			(stroke
				(width 0.1)
				(type default)
			)
			(layer "F.Fab")
		)
		(fp_line
			(start 0.67945 -0.3048)
			(end 0.67945 0.3048)
			(stroke
				(width 0.1)
				(type default)
			)
			(layer "F.Fab")
		)
		(fp_line
			(start 0.12065 -0.3048)
			(end 0.67945 -0.3048)
			(stroke
				(width 0.1)
				(type default)
			)
			(layer "F.Fab")
		)
		(fp_line
			(start 0.12065 -0.2794)
			(end 0.12065 -0.3048)
			(stroke
				(width 0.1)
				(type default)
			)
			(layer "F.Fab")
		)
		(fp_line
			(start -0.12065 -0.2794)
			(end 0.12065 -0.2794)
			(stroke
				(width 0.1)
				(type default)
			)
			(layer "F.Fab")
		)
		(fp_line
			(start 0.120396 0.2794)
			(end -0.12065 0.2794)
			(stroke
				(width 0.1)
				(type default)
			)
			(layer "F.Fab")
		)
		(fp_line
			(start -0.12065 0.2794)
			(end -0.12065 0.3048)
			(stroke
				(width 0.1)
				(type default)
			)
			(layer "F.Fab")
		)
		(fp_line
			(start 0.67945 0.3048)
			(end 0.120396 0.3048)
			(stroke
				(width 0.1)
				(type default)
			)
			(layer "F.Fab")
		)
		(fp_line
			(start 0.120396 0.3048)
			(end 0.120396 0.2794)
			(stroke
				(width 0.1)
				(type default)
			)
			(layer "F.Fab")
		)
		(fp_line
			(start -0.12065 0.3048)
			(end -0.67945 0.3048)
			(stroke
				(width 0.1)
				(type default)
			)
			(layer "F.Fab")
		)
		(fp_line
			(start -0.67945 0.3048)
			(end -0.67945 -0.305054)
			(stroke
				(width 0.1)
				(type default)
			)
			(layer "F.Fab")
		)
		(pad "1" smd circle
			(at -0.40005 0 90)
			(size 0 0)
			(layers "F.Cu" "F.Mask" "F.Paste")
			(net "U272_2_ADD1")
		)
		(pad "2" smd circle
			(at 0.40005 0 90)
			(size 0 0)
			(layers "F.Cu" "F.Mask" "F.Paste")
			(net "GND")
		)
	)
	(footprint ""
		(layer "F.Cu")
		(at 187.11037 -355.705156)
		(property "Reference" "PC509_1"
			(at 0 0 0)
			(layer "F.SilkS")
			(hide yes)
			(effects
				(font
					(size 1.27 1.27)
				)
			)
		)
		(property "Value" ""
			(at 0 0 0)
			(layer "F.Fab")
			(effects
				(font
					(size 1.27 1.27)
				)
			)
		)
		(duplicate_pad_numbers_are_jumpers no)
		(fp_line
			(start -0.7874 -0.4064)
			(end 0.7874 -0.4064)
			(stroke
				(width 0.1524)
				(type default)
			)
			(layer "F.SilkS")
		)
		(fp_line
			(start -0.7874 0.4064)
			(end -0.7874 -0.4064)
			(stroke
				(width 0.1524)
				(type default)
			)
			(layer "F.SilkS")
		)
		(fp_line
			(start 0.7874 -0.4064)
			(end 0.7874 0.4064)
			(stroke
				(width 0.1524)
				(type default)
			)
			(layer "F.SilkS")
		)
		(fp_line
			(start 0.7874 0.4064)
			(end -0.7874 0.4064)
			(stroke
				(width 0.1524)
				(type default)
			)
			(layer "F.SilkS")
		)
		(fp_line
			(start -0.67945 -0.305054)
			(end -0.12065 -0.305054)
			(stroke
				(width 0.1)
				(type default)
			)
			(layer "F.Fab")
		)
		(fp_line
			(start -0.67945 0.3048)
			(end -0.67945 -0.305054)
			(stroke
				(width 0.1)
				(type default)
			)
			(layer "F.Fab")
		)
		(fp_line
			(start -0.12065 -0.305054)
			(end -0.12065 -0.2794)
			(stroke
				(width 0.1)
				(type default)
			)
			(layer "F.Fab")
		)
		(fp_line
			(start -0.12065 -0.2794)
			(end 0.12065 -0.2794)
			(stroke
				(width 0.1)
				(type default)
			)
			(layer "F.Fab")
		)
		(fp_line
			(start -0.12065 0.2794)
			(end -0.12065 0.3048)
			(stroke
				(width 0.1)
				(type default)
			)
			(layer "F.Fab")
		)
		(fp_line
			(start -0.12065 0.3048)
			(end -0.67945 0.3048)
			(stroke
				(width 0.1)
				(type default)
			)
			(layer "F.Fab")
		)
		(fp_line
			(start 0.120396 0.2794)
			(end -0.12065 0.2794)
			(stroke
				(width 0.1)
				(type default)
			)
			(layer "F.Fab")
		)
		(fp_line
			(start 0.120396 0.3048)
			(end 0.120396 0.2794)
			(stroke
				(width 0.1)
				(type default)
			)
			(layer "F.Fab")
		)
		(fp_line
			(start 0.12065 -0.3048)
			(end 0.67945 -0.3048)
			(stroke
				(width 0.1)
				(type default)
			)
			(layer "F.Fab")
		)
		(fp_line
			(start 0.12065 -0.2794)
			(end 0.12065 -0.3048)
			(stroke
				(width 0.1)
				(type default)
			)
			(layer "F.Fab")
		)
		(fp_line
			(start 0.67945 -0.3048)
			(end 0.67945 0.3048)
			(stroke
				(width 0.1)
				(type default)
			)
			(layer "F.Fab")
		)
		(fp_line
			(start 0.67945 0.3048)
			(end 0.120396 0.3048)
			(stroke
				(width 0.1)
				(type default)
			)
			(layer "F.Fab")
		)
		(pad "1" smd circle
			(at -0.40005 0)
			(size 0 0)
			(layers "F.Cu" "F.Mask" "F.Paste")
			(net "SW_P12V_AUX_PVDD11_S3_P1_FLT")
		)
		(pad "2" smd circle
			(at 0.40005 0)
			(size 0 0)
			(layers "F.Cu" "F.Mask" "F.Paste")
			(net "GND")
		)
	)
	(footprint ""
		(layer "F.Cu")
		(at 28.288488 -437.458358 180)
		(property "Reference" "U200"
			(at 3.169412 2.695194 0)
			(unlocked yes)
			(layer "F.SilkS")
			(effects
				(font
					(size 0.7874 0.5842)
					(thickness 0.1524)
				)
				(justify left)
			)
		)
		(property "Value" ""
			(at 0 0 180)
			(layer "F.Fab")
			(effects
				(font
					(size 1.27 1.27)
				)
			)
		)
		(duplicate_pad_numbers_are_jumpers no)
		(fp_line
			(start 1.3716 1.524)
			(end -1.3716 1.524)
			(stroke
				(width 0.1524)
				(type default)
			)
			(layer "F.SilkS")
		)
		(fp_line
			(start 1.3716 -1.524)
			(end 1.3716 1.524)
			(stroke
				(width 0.1524)
				(type default)
			)
			(layer "F.SilkS")
		)
		(fp_line
			(start 0.508 -1.524)
			(end 1.3716 -1.524)
			(stroke
				(width 0.1524)
				(type default)
			)
			(layer "F.SilkS")
		)
		(fp_line
			(start 0 -1.016)
			(end 0.508 -1.524)
			(stroke
				(width 0.1524)
				(type default)
			)
			(layer "F.SilkS")
		)
		(fp_line
			(start -0.508 -1.524)
			(end 0 -1.016)
			(stroke
				(width 0.1524)
				(type default)
			)
			(layer "F.SilkS")
		)
		(fp_line
			(start -1.3716 1.524)
			(end -1.3716 -1.524)
			(stroke
				(width 0.1524)
				(type default)
			)
			(layer "F.SilkS")
		)
		(fp_line
			(start -1.3716 -1.524)
			(end -0.508 -1.524)
			(stroke
				(width 0.1524)
				(type default)
			)
			(layer "F.SilkS")
		)
		(fp_poly
			(pts
				(xy -4.108704 -0.70358) (xy -4.108704 -1.32842) (xy -3.554984 -1.000252)
			)
			(stroke
				(width 0)
				(type default)
			)
			(fill yes)
			(layer "F.SilkS")
		)
		(fp_line
			(start 2.54 1.0668)
			(end 1.5494 1.0668)
			(stroke
				(width 0.1)
				(type default)
			)
			(layer "F.Fab")
		)
		(fp_line
			(start 2.54 -1.0668)
			(end 2.54 1.0668)
			(stroke
				(width 0.1)
				(type default)
			)
			(layer "F.Fab")
		)
		(fp_line
			(start 1.5494 1.524)
			(end -1.5494 1.524)
			(stroke
				(width 0.1)
				(type default)
			)
			(layer "F.Fab")
		)
		(fp_line
			(start 1.5494 1.0668)
			(end 1.5494 1.524)
			(stroke
				(width 0.1)
				(type default)
			)
			(layer "F.Fab")
		)
		(fp_line
			(start 1.5494 -1.0668)
			(end 2.54 -1.0668)
			(stroke
				(width 0.1)
				(type default)
			)
			(layer "F.Fab")
		)
		(fp_line
			(start 1.5494 -1.0668)
			(end 1.5494 1.0668)
			(stroke
				(width 0.1)
				(type default)
			)
			(layer "F.Fab")
		)
		(fp_line
			(start 1.5494 -1.524)
			(end 1.5494 -1.0668)
			(stroke
				(width 0.1)
				(type default)
			)
			(layer "F.Fab")
		)
		(fp_line
			(start -1.5494 1.524)
			(end -1.5494 1.0668)
			(stroke
				(width 0.1)
				(type default)
			)
			(layer "F.Fab")
		)
		(fp_line
			(start -1.5494 1.0668)
			(end -1.5494 -1.0668)
			(stroke
				(width 0.1)
				(type default)
			)
			(layer "F.Fab")
		)
		(fp_line
			(start -1.5494 1.0668)
			(end -2.54 1.0668)
			(stroke
				(width 0.1)
				(type default)
			)
			(layer "F.Fab")
		)
		(fp_line
			(start -1.5494 -1.0668)
			(end -1.5494 -1.524)
			(stroke
				(width 0.1)
				(type default)
			)
			(layer "F.Fab")
		)
		(fp_line
			(start -1.5494 -1.524)
			(end 1.5494 -1.524)
			(stroke
				(width 0.1)
				(type default)
			)
			(layer "F.Fab")
		)
		(fp_line
			(start -2.54 1.0668)
			(end -2.54 -1.0668)
			(stroke
				(width 0.1)
				(type default)
			)
			(layer "F.Fab")
		)
		(fp_line
			(start -2.54 -1.0668)
			(end -1.5494 -1.0668)
			(stroke
				(width 0.1)
				(type default)
			)
			(layer "F.Fab")
		)
		(fp_poly
			(pts
				(xy -3.60172 -0.719328) (xy -3.60172 -1.344168) (xy -3.048 -1.016)
			)
			(stroke
				(width 0)
				(type default)
			)
			(fill yes)
			(layer "F.Fab")
		)
		(pad "1" smd rect
			(at -2.232406 -0.975106 90)
			(size 0.3556 1.4224)
			(layers "F.Cu" "F.Mask" "F.Paste")
			(net "SMB_BMC_GPU_EN_R3")
		)
		(pad "2" smd rect
			(at -2.232406 -0.32512 90)
			(size 0.3556 1.4224)
			(layers "F.Cu" "F.Mask" "F.Paste")
			(net "SMB_2_BMC_GPU_BUF_R_SCL")
		)
		(pad "3" smd rect
			(at -2.232406 0.32512 90)
			(size 0.3556 1.4224)
			(layers "F.Cu" "F.Mask" "F.Paste")
			(net "SMB_2_BMC_GPU_R_SCL")
		)
		(pad "4" smd rect
			(at -2.232406 0.975106 90)
			(size 0.3556 1.4224)
			(layers "F.Cu" "F.Mask" "F.Paste")
			(net "GND")
		)
		(pad "5" smd rect
			(at 2.232406 0.975106 90)
			(size 0.3556 1.4224)
			(layers "F.Cu" "F.Mask" "F.Paste")
			(net "Net_10759")
		)
		(pad "6" smd rect
			(at 2.232406 0.32512 90)
			(size 0.3556 1.4224)
			(layers "F.Cu" "F.Mask" "F.Paste")
			(net "SMB_2_BMC_GPU_R_SDA")
		)
		(pad "7" smd rect
			(at 2.232406 -0.32512 90)
			(size 0.3556 1.4224)
			(layers "F.Cu" "F.Mask" "F.Paste")
			(net "SMB_2_BMC_GPU_BUF_R_SDA")
		)
		(pad "8" smd rect
			(at 2.232406 -0.975106 90)
			(size 0.3556 1.4224)
			(layers "F.Cu" "F.Mask" "F.Paste")
			(net "P3V3_AUX")
		)
	)
	(footprint ""
		(layer "F.Cu")
		(at 190.119 -133.568948 90)
		(property "Reference" "R708"
			(at 0 0 90)
			(layer "F.SilkS")
			(hide yes)
			(effects
				(font
					(size 1.27 1.27)
				)
			)
		)
		(property "Value" ""
			(at 0 0 90)
			(layer "F.Fab")
			(effects
				(font
					(size 1.27 1.27)
				)
			)
		)
		(duplicate_pad_numbers_are_jumpers no)
		(fp_line
			(start 0.7874 -0.4064)
			(end 0.7874 0.4064)
			(stroke
				(width 0.1524)
				(type default)
			)
			(layer "F.SilkS")
		)
		(fp_line
			(start -0.7874 -0.4064)
			(end 0.7874 -0.4064)
			(stroke
				(width 0.1524)
				(type default)
			)
			(layer "F.SilkS")
		)
		(fp_line
			(start 0.7874 0.4064)
			(end -0.7874 0.4064)
			(stroke
				(width 0.1524)
				(type default)
			)
			(layer "F.SilkS")
		)
		(fp_line
			(start -0.7874 0.4064)
			(end -0.7874 -0.4064)
			(stroke
				(width 0.1524)
				(type default)
			)
			(layer "F.SilkS")
		)
		(fp_line
			(start -0.12065 -0.305054)
			(end -0.12065 -0.2794)
			(stroke
				(width 0.1)
				(type default)
			)
			(layer "F.Fab")
		)
		(fp_line
			(start -0.67945 -0.305054)
			(end -0.12065 -0.305054)
			(stroke
				(width 0.1)
				(type default)
			)
			(layer "F.Fab")
		)
		(fp_line
			(start 0.67945 -0.3048)
			(end 0.67945 0.3048)
			(stroke
				(width 0.1)
				(type default)
			)
			(layer "F.Fab")
		)
		(fp_line
			(start 0.12065 -0.3048)
			(end 0.67945 -0.3048)
			(stroke
				(width 0.1)
				(type default)
			)
			(layer "F.Fab")
		)
		(fp_line
			(start 0.12065 -0.2794)
			(end 0.12065 -0.3048)
			(stroke
				(width 0.1)
				(type default)
			)
			(layer "F.Fab")
		)
		(fp_line
			(start -0.12065 -0.2794)
			(end 0.12065 -0.2794)
			(stroke
				(width 0.1)
				(type default)
			)
			(layer "F.Fab")
		)
		(fp_line
			(start 0.120396 0.2794)
			(end -0.12065 0.2794)
			(stroke
				(width 0.1)
				(type default)
			)
			(layer "F.Fab")
		)
		(fp_line
			(start -0.12065 0.2794)
			(end -0.12065 0.3048)
			(stroke
				(width 0.1)
				(type default)
			)
			(layer "F.Fab")
		)
		(fp_line
			(start 0.67945 0.3048)
			(end 0.120396 0.3048)
			(stroke
				(width 0.1)
				(type default)
			)
			(layer "F.Fab")
		)
		(fp_line
			(start 0.120396 0.3048)
			(end 0.120396 0.2794)
			(stroke
				(width 0.1)
				(type default)
			)
			(layer "F.Fab")
		)
		(fp_line
			(start -0.12065 0.3048)
			(end -0.67945 0.3048)
			(stroke
				(width 0.1)
				(type default)
			)
			(layer "F.Fab")
		)
		(fp_line
			(start -0.67945 0.3048)
			(end -0.67945 -0.305054)
			(stroke
				(width 0.1)
				(type default)
			)
			(layer "F.Fab")
		)
		(pad "1" smd circle
			(at -0.40005 0 90)
			(size 0 0)
			(layers "F.Cu" "F.Mask" "F.Paste")
			(net "FM_HDT_HDR_PWROK")
		)
		(pad "2" smd circle
			(at 0.40005 0 90)
			(size 0 0)
			(layers "F.Cu" "F.Mask" "F.Paste")
			(net "HDT_HDR_PWROK")
		)
	)
	(footprint ""
		(layer "F.Cu")
		(at 402.356066 -143.029432 -90)
		(property "Reference" "C1042"
			(at 0 0 270)
			(layer "F.SilkS")
			(hide yes)
			(effects
				(font
					(size 1.27 1.27)
				)
			)
		)
		(property "Value" ""
			(at 0 0 270)
			(layer "F.Fab")
			(effects
				(font
					(size 1.27 1.27)
				)
			)
		)
		(duplicate_pad_numbers_are_jumpers no)
		(fp_line
			(start -0.7874 0.4064)
			(end -0.7874 -0.4064)
			(stroke
				(width 0.1524)
				(type default)
			)
			(layer "F.SilkS")
		)
		(fp_line
			(start 0.7874 0.4064)
			(end -0.7874 0.4064)
			(stroke
				(width 0.1524)
				(type default)
			)
			(layer "F.SilkS")
		)
		(fp_line
			(start -0.7874 -0.4064)
			(end 0.7874 -0.4064)
			(stroke
				(width 0.1524)
				(type default)
			)
			(layer "F.SilkS")
		)
		(fp_line
			(start 0.7874 -0.4064)
			(end 0.7874 0.4064)
			(stroke
				(width 0.1524)
				(type default)
			)
			(layer "F.SilkS")
		)
		(fp_line
			(start -0.67945 0.3048)
			(end -0.67945 -0.305054)
			(stroke
				(width 0.1)
				(type default)
			)
			(layer "F.Fab")
		)
		(fp_line
			(start -0.12065 0.3048)
			(end -0.67945 0.3048)
			(stroke
				(width 0.1)
				(type default)
			)
			(layer "F.Fab")
		)
		(fp_line
			(start 0.120396 0.3048)
			(end 0.120396 0.2794)
			(stroke
				(width 0.1)
				(type default)
			)
			(layer "F.Fab")
		)
		(fp_line
			(start 0.67945 0.3048)
			(end 0.120396 0.3048)
			(stroke
				(width 0.1)
				(type default)
			)
			(layer "F.Fab")
		)
		(fp_line
			(start -0.12065 0.2794)
			(end -0.12065 0.3048)
			(stroke
				(width 0.1)
				(type default)
			)
			(layer "F.Fab")
		)
		(fp_line
			(start 0.120396 0.2794)
			(end -0.12065 0.2794)
			(stroke
				(width 0.1)
				(type default)
			)
			(layer "F.Fab")
		)
		(fp_line
			(start -0.12065 -0.2794)
			(end 0.12065 -0.2794)
			(stroke
				(width 0.1)
				(type default)
			)
			(layer "F.Fab")
		)
		(fp_line
			(start 0.12065 -0.2794)
			(end 0.12065 -0.3048)
			(stroke
				(width 0.1)
				(type default)
			)
			(layer "F.Fab")
		)
		(fp_line
			(start 0.12065 -0.3048)
			(end 0.67945 -0.3048)
			(stroke
				(width 0.1)
				(type default)
			)
			(layer "F.Fab")
		)
		(fp_line
			(start 0.67945 -0.3048)
			(end 0.67945 0.3048)
			(stroke
				(width 0.1)
				(type default)
			)
			(layer "F.Fab")
		)
		(fp_line
			(start -0.67945 -0.305054)
			(end -0.12065 -0.305054)
			(stroke
				(width 0.1)
				(type default)
			)
			(layer "F.Fab")
		)
		(fp_line
			(start -0.12065 -0.305054)
			(end -0.12065 -0.2794)
			(stroke
				(width 0.1)
				(type default)
			)
			(layer "F.Fab")
		)
		(pad "1" smd circle
			(at -0.40005 0 270)
			(size 0 0)
			(layers "F.Cu" "F.Mask" "F.Paste")
			(net "P5V_AUX")
		)
		(pad "2" smd circle
			(at 0.40005 0 270)
			(size 0 0)
			(layers "F.Cu" "F.Mask" "F.Paste")
			(net "GND")
		)
	)
)
